(kicad_pcb
	(version 20260206)
	(generator "pcbnew")
	(generator_version "10.0")
	(general
		(thickness 1.6)
		(legacy_teardrops no)
	)
	(paper "A4")
	(title_block
		(title "04192023_DAF0TMB3IC0_F0TG_MB_C_brd_V02_OCP.brd")
		(comment 1 "Grand Teton / footprints 2049-2054 of 8354")
	)
	(layers
		(0 "F.Cu" signal "TOP")
		(4 "In1.Cu" signal "GND")
		(6 "In2.Cu" signal "IN1")
		(8 "In3.Cu" signal "GND1")
		(10 "In4.Cu" signal "IN2")
		(12 "In5.Cu" signal "GND2")
		(14 "In6.Cu" signal "IN3")
		(16 "In7.Cu" signal "GND3")
		(18 "In8.Cu" signal "VCC")
		(20 "In9.Cu" signal "VCC1")
		(22 "In10.Cu" signal "GND4")
		(24 "In11.Cu" signal "IN4")
		(26 "In12.Cu" signal "GND5")
		(28 "In13.Cu" signal "IN5")
		(30 "In14.Cu" signal "GND6")
		(32 "In15.Cu" signal "IN6")
		(34 "In16.Cu" signal "GND7")
		(2 "B.Cu" signal "BOTTOM")
		(9 "F.Adhes" user "F.Adhesive")
		(11 "B.Adhes" user "B.Adhesive")
		(13 "F.Paste" user "Package Geometry/Pastemask Top")
		(15 "B.Paste" user "Package Geometry/Pastemask Bottom")
		(5 "F.SilkS" user "Ref Des/Silkscreen Top")
		(7 "B.SilkS" user "Ref Des/Silkscreen Bottom")
		(1 "F.Mask" user "Board Geometry/Soldermask Top")
		(3 "B.Mask" user "Board Geometry/Soldermask Bottom")
		(17 "Dwgs.User" user "User.Drawings")
		(19 "Cmts.User" user "User.Comments")
		(21 "Eco1.User" user "User.Eco1")
		(23 "Eco2.User" user "User.Eco2")
		(25 "Edge.Cuts" user "Board Geometry/Outline")
		(27 "Margin" user)
		(31 "F.CrtYd" user "Package Geometry/Place Bound Top")
		(29 "B.CrtYd" user "Package Geometry/Place Bound Bottom")
		(35 "F.Fab" user "Ref Des/Assembly Top")
		(33 "B.Fab" user "Ref Des/Assembly Bottom")
	)
	(footprint ""
		(layer "F.Cu")
		(at 294.769794 -18.780506 180)
		(property "Reference" "C73"
			(at 0 0 180)
			(layer "F.SilkS")
			(hide yes)
			(effects
				(font
					(size 1.27 1.27)
				)
			)
		)
		(property "Value" ""
			(at 0 0 180)
			(layer "F.Fab")
			(effects
				(font
					(size 1.27 1.27)
				)
			)
		)
		(duplicate_pad_numbers_are_jumpers no)
		(fp_line
			(start 0.7874 0.4064)
			(end -0.7874 0.4064)
			(stroke
				(width 0.1524)
				(type default)
			)
			(layer "F.SilkS")
		)
		(fp_line
			(start 0.7874 -0.4064)
			(end 0.7874 0.4064)
			(stroke
				(width 0.1524)
				(type default)
			)
			(layer "F.SilkS")
		)
		(fp_line
			(start -0.7874 0.4064)
			(end -0.7874 -0.4064)
			(stroke
				(width 0.1524)
				(type default)
			)
			(layer "F.SilkS")
		)
		(fp_line
			(start -0.7874 -0.4064)
			(end 0.7874 -0.4064)
			(stroke
				(width 0.1524)
				(type default)
			)
			(layer "F.SilkS")
		)
		(fp_line
			(start 0.67945 0.3048)
			(end 0.120396 0.3048)
			(stroke
				(width 0.1)
				(type default)
			)
			(layer "F.Fab")
		)
		(fp_line
			(start 0.67945 -0.3048)
			(end 0.67945 0.3048)
			(stroke
				(width 0.1)
				(type default)
			)
			(layer "F.Fab")
		)
		(fp_line
			(start 0.12065 -0.2794)
			(end 0.12065 -0.3048)
			(stroke
				(width 0.1)
				(type default)
			)
			(layer "F.Fab")
		)
		(fp_line
			(start 0.12065 -0.3048)
			(end 0.67945 -0.3048)
			(stroke
				(width 0.1)
				(type default)
			)
			(layer "F.Fab")
		)
		(fp_line
			(start 0.120396 0.3048)
			(end 0.120396 0.2794)
			(stroke
				(width 0.1)
				(type default)
			)
			(layer "F.Fab")
		)
		(fp_line
			(start 0.120396 0.2794)
			(end -0.12065 0.2794)
			(stroke
				(width 0.1)
				(type default)
			)
			(layer "F.Fab")
		)
		(fp_line
			(start -0.12065 0.3048)
			(end -0.67945 0.3048)
			(stroke
				(width 0.1)
				(type default)
			)
			(layer "F.Fab")
		)
		(fp_line
			(start -0.12065 0.2794)
			(end -0.12065 0.3048)
			(stroke
				(width 0.1)
				(type default)
			)
			(layer "F.Fab")
		)
		(fp_line
			(start -0.12065 -0.2794)
			(end 0.12065 -0.2794)
			(stroke
				(width 0.1)
				(type default)
			)
			(layer "F.Fab")
		)
		(fp_line
			(start -0.12065 -0.305054)
			(end -0.12065 -0.2794)
			(stroke
				(width 0.1)
				(type default)
			)
			(layer "F.Fab")
		)
		(fp_line
			(start -0.67945 0.3048)
			(end -0.67945 -0.305054)
			(stroke
				(width 0.1)
				(type default)
			)
			(layer "F.Fab")
		)
		(fp_line
			(start -0.67945 -0.305054)
			(end -0.12065 -0.305054)
			(stroke
				(width 0.1)
				(type default)
			)
			(layer "F.Fab")
		)
		(pad "1" smd circle
			(at -0.40005 0 180)
			(size 0 0)
			(layers "F.Cu" "F.Mask" "F.Paste")
			(net "P3V3_AUX")
		)
		(pad "2" smd circle
			(at 0.40005 0 180)
			(size 0 0)
			(layers "F.Cu" "F.Mask" "F.Paste")
			(net "GND")
		)
	)
	(footprint ""
		(layer "F.Cu")
		(at 113.20653 -15.879064)
		(property "Reference" "U273"
			(at 1.29413 -3.490214 0)
			(unlocked yes)
			(layer "F.SilkS")
			(effects
				(font
					(size 0.7874 0.5842)
					(thickness 0.1524)
				)
				(justify left)
			)
		)
		(property "Value" ""
			(at 0 0 0)
			(layer "F.Fab")
			(effects
				(font
					(size 1.27 1.27)
				)
			)
		)
		(duplicate_pad_numbers_are_jumpers no)
		(fp_line
			(start -3.447796 -2.500122)
			(end -3.447796 2.500122)
			(stroke
				(width 0.1524)
				(type default)
			)
			(layer "F.SilkS")
		)
		(fp_line
			(start -3.447796 2.500122)
			(end 3.447796 2.500122)
			(stroke
				(width 0.1524)
				(type default)
			)
			(layer "F.SilkS")
		)
		(fp_line
			(start -1.484122 -2.500122)
			(end -3.447796 -2.500122)
			(stroke
				(width 0.1524)
				(type default)
			)
			(layer "F.SilkS")
		)
		(fp_line
			(start 0 -1.016)
			(end -1.484122 -2.500122)
			(stroke
				(width 0.1524)
				(type default)
			)
			(layer "F.SilkS")
		)
		(fp_line
			(start 1.484122 -2.500122)
			(end 0 -1.016)
			(stroke
				(width 0.1524)
				(type default)
			)
			(layer "F.SilkS")
		)
		(fp_line
			(start 3.447796 -2.500122)
			(end 1.484122 -2.500122)
			(stroke
				(width 0.1524)
				(type default)
			)
			(layer "F.SilkS")
		)
		(fp_line
			(start 3.447796 2.500122)
			(end 3.447796 -2.500122)
			(stroke
				(width 0.1524)
				(type default)
			)
			(layer "F.SilkS")
		)
		(fp_poly
			(pts
				(xy -4.670552 -0.917702) (xy -4.901184 -1.907032) (xy -3.796538 -1.64338)
			)
			(stroke
				(width 0)
				(type default)
			)
			(fill yes)
			(layer "F.SilkS")
		)
		(fp_line
			(start -1.999996 -2.500122)
			(end -1.999996 2.500122)
			(stroke
				(width 0.1)
				(type default)
			)
			(layer "F.Fab")
		)
		(fp_line
			(start -1.999996 2.500122)
			(end 1.999996 2.500122)
			(stroke
				(width 0.1)
				(type default)
			)
			(layer "F.Fab")
		)
		(fp_line
			(start 1.999996 -2.500122)
			(end -1.999996 -2.500122)
			(stroke
				(width 0.1)
				(type default)
			)
			(layer "F.Fab")
		)
		(fp_line
			(start 1.999996 2.500122)
			(end 1.999996 -2.500122)
			(stroke
				(width 0.1)
				(type default)
			)
			(layer "F.Fab")
		)
		(fp_poly
			(pts
				(xy -4.5974 -2.413) (xy -4.5974 -1.397) (xy -3.5814 -1.905)
			)
			(stroke
				(width 0)
				(type default)
			)
			(fill yes)
			(layer "F.Fab")
		)
		(pad "1" smd rect
			(at -2.649982 -1.905 270)
			(size 0.6096 1.3208)
			(layers "F.Cu" "F.Mask" "F.Paste")
			(net "SMB_LM75_3_3V3AUX_SDA_R1")
		)
		(pad "2" smd rect
			(at -2.649982 -0.635 270)
			(size 0.6096 1.3208)
			(layers "F.Cu" "F.Mask" "F.Paste")
			(net "SMB_LM75_3_3V3AUX_SCL_R1")
		)
		(pad "3" smd rect
			(at -2.649982 0.635 270)
			(size 0.6096 1.3208)
			(layers "F.Cu" "F.Mask" "F.Paste")
			(net "FM_LM75_3_ALERT_N")
		)
		(pad "4" smd rect
			(at -2.649982 1.905 270)
			(size 0.6096 1.3208)
			(layers "F.Cu" "F.Mask" "F.Paste")
			(net "GND")
		)
		(pad "5" smd rect
			(at 2.649982 1.905 270)
			(size 0.6096 1.3208)
			(layers "F.Cu" "F.Mask" "F.Paste")
			(net "U273_3_ADD2")
		)
		(pad "6" smd rect
			(at 2.649982 0.635 270)
			(size 0.6096 1.3208)
			(layers "F.Cu" "F.Mask" "F.Paste")
			(net "U273_3_ADD1")
		)
		(pad "7" smd rect
			(at 2.649982 -0.635 270)
			(size 0.6096 1.3208)
			(layers "F.Cu" "F.Mask" "F.Paste")
			(net "U273_3_ADD0")
		)
		(pad "8" smd rect
			(at 2.649982 -1.905 270)
			(size 0.6096 1.3208)
			(layers "F.Cu" "F.Mask" "F.Paste")
			(net "P3V3_AUX")
		)
	)
	(footprint ""
		(layer "F.Cu")
		(at 105.64876 -58.502042 180)
		(property "Reference" "R1737"
			(at 0 0 180)
			(layer "F.SilkS")
			(hide yes)
			(effects
				(font
					(size 1.27 1.27)
				)
			)
		)
		(property "Value" ""
			(at 0 0 180)
			(layer "F.Fab")
			(effects
				(font
					(size 1.27 1.27)
				)
			)
		)
		(duplicate_pad_numbers_are_jumpers no)
		(fp_line
			(start 0.7874 0.4064)
			(end -0.7874 0.4064)
			(stroke
				(width 0.1524)
				(type default)
			)
			(layer "F.SilkS")
		)
		(fp_line
			(start 0.7874 -0.4064)
			(end 0.7874 0.4064)
			(stroke
				(width 0.1524)
				(type default)
			)
			(layer "F.SilkS")
		)
		(fp_line
			(start -0.7874 0.4064)
			(end -0.7874 -0.4064)
			(stroke
				(width 0.1524)
				(type default)
			)
			(layer "F.SilkS")
		)
		(fp_line
			(start -0.7874 -0.4064)
			(end 0.7874 -0.4064)
			(stroke
				(width 0.1524)
				(type default)
			)
			(layer "F.SilkS")
		)
		(fp_line
			(start 0.67945 0.3048)
			(end 0.120396 0.3048)
			(stroke
				(width 0.1)
				(type default)
			)
			(layer "F.Fab")
		)
		(fp_line
			(start 0.67945 -0.3048)
			(end 0.67945 0.3048)
			(stroke
				(width 0.1)
				(type default)
			)
			(layer "F.Fab")
		)
		(fp_line
			(start 0.12065 -0.2794)
			(end 0.12065 -0.3048)
			(stroke
				(width 0.1)
				(type default)
			)
			(layer "F.Fab")
		)
		(fp_line
			(start 0.12065 -0.3048)
			(end 0.67945 -0.3048)
			(stroke
				(width 0.1)
				(type default)
			)
			(layer "F.Fab")
		)
		(fp_line
			(start 0.120396 0.3048)
			(end 0.120396 0.2794)
			(stroke
				(width 0.1)
				(type default)
			)
			(layer "F.Fab")
		)
		(fp_line
			(start 0.120396 0.2794)
			(end -0.12065 0.2794)
			(stroke
				(width 0.1)
				(type default)
			)
			(layer "F.Fab")
		)
		(fp_line
			(start -0.12065 0.3048)
			(end -0.67945 0.3048)
			(stroke
				(width 0.1)
				(type default)
			)
			(layer "F.Fab")
		)
		(fp_line
			(start -0.12065 0.2794)
			(end -0.12065 0.3048)
			(stroke
				(width 0.1)
				(type default)
			)
			(layer "F.Fab")
		)
		(fp_line
			(start -0.12065 -0.2794)
			(end 0.12065 -0.2794)
			(stroke
				(width 0.1)
				(type default)
			)
			(layer "F.Fab")
		)
		(fp_line
			(start -0.12065 -0.305054)
			(end -0.12065 -0.2794)
			(stroke
				(width 0.1)
				(type default)
			)
			(layer "F.Fab")
		)
		(fp_line
			(start -0.67945 0.3048)
			(end -0.67945 -0.305054)
			(stroke
				(width 0.1)
				(type default)
			)
			(layer "F.Fab")
		)
		(fp_line
			(start -0.67945 -0.305054)
			(end -0.12065 -0.305054)
			(stroke
				(width 0.1)
				(type default)
			)
			(layer "F.Fab")
		)
		(pad "1" smd circle
			(at -0.40005 0 180)
			(size 0 0)
			(layers "F.Cu" "F.Mask" "F.Paste")
			(net "JTAG_SCM_MUX_R_TMS")
		)
		(pad "2" smd circle
			(at 0.40005 0 180)
			(size 0 0)
			(layers "F.Cu" "F.Mask" "F.Paste")
			(net "JTAG_SCM_MUX_TMS")
		)
	)
	(footprint ""
		(layer "F.Cu")
		(at 455.01306 -42.121836)
		(property "Reference" "R5487"
			(at 0 0 0)
			(layer "F.SilkS")
			(hide yes)
			(effects
				(font
					(size 1.27 1.27)
				)
			)
		)
		(property "Value" ""
			(at 0 0 0)
			(layer "F.Fab")
			(effects
				(font
					(size 1.27 1.27)
				)
			)
		)
		(duplicate_pad_numbers_are_jumpers no)
		(fp_line
			(start -0.7874 -0.4064)
			(end 0.7874 -0.4064)
			(stroke
				(width 0.1524)
				(type default)
			)
			(layer "F.SilkS")
		)
		(fp_line
			(start -0.7874 0.4064)
			(end -0.7874 -0.4064)
			(stroke
				(width 0.1524)
				(type default)
			)
			(layer "F.SilkS")
		)
		(fp_line
			(start 0.7874 -0.4064)
			(end 0.7874 0.4064)
			(stroke
				(width 0.1524)
				(type default)
			)
			(layer "F.SilkS")
		)
		(fp_line
			(start 0.7874 0.4064)
			(end -0.7874 0.4064)
			(stroke
				(width 0.1524)
				(type default)
			)
			(layer "F.SilkS")
		)
		(fp_line
			(start -0.67945 -0.305054)
			(end -0.12065 -0.305054)
			(stroke
				(width 0.1)
				(type default)
			)
			(layer "F.Fab")
		)
		(fp_line
			(start -0.67945 0.3048)
			(end -0.67945 -0.305054)
			(stroke
				(width 0.1)
				(type default)
			)
			(layer "F.Fab")
		)
		(fp_line
			(start -0.12065 -0.305054)
			(end -0.12065 -0.2794)
			(stroke
				(width 0.1)
				(type default)
			)
			(layer "F.Fab")
		)
		(fp_line
			(start -0.12065 -0.2794)
			(end 0.12065 -0.2794)
			(stroke
				(width 0.1)
				(type default)
			)
			(layer "F.Fab")
		)
		(fp_line
			(start -0.12065 0.2794)
			(end -0.12065 0.3048)
			(stroke
				(width 0.1)
				(type default)
			)
			(layer "F.Fab")
		)
		(fp_line
			(start -0.12065 0.3048)
			(end -0.67945 0.3048)
			(stroke
				(width 0.1)
				(type default)
			)
			(layer "F.Fab")
		)
		(fp_line
			(start 0.120396 0.2794)
			(end -0.12065 0.2794)
			(stroke
				(width 0.1)
				(type default)
			)
			(layer "F.Fab")
		)
		(fp_line
			(start 0.120396 0.3048)
			(end 0.120396 0.2794)
			(stroke
				(width 0.1)
				(type default)
			)
			(layer "F.Fab")
		)
		(fp_line
			(start 0.12065 -0.3048)
			(end 0.67945 -0.3048)
			(stroke
				(width 0.1)
				(type default)
			)
			(layer "F.Fab")
		)
		(fp_line
			(start 0.12065 -0.2794)
			(end 0.12065 -0.3048)
			(stroke
				(width 0.1)
				(type default)
			)
			(layer "F.Fab")
		)
		(fp_line
			(start 0.67945 -0.3048)
			(end 0.67945 0.3048)
			(stroke
				(width 0.1)
				(type default)
			)
			(layer "F.Fab")
		)
		(fp_line
			(start 0.67945 0.3048)
			(end 0.120396 0.3048)
			(stroke
				(width 0.1)
				(type default)
			)
			(layer "F.Fab")
		)
		(pad "1" smd circle
			(at -0.40005 0)
			(size 0 0)
			(layers "F.Cu" "F.Mask" "F.Paste")
			(net "P3V3_OCP_SFF_EN_R")
		)
		(pad "2" smd circle
			(at 0.40005 0)
			(size 0 0)
			(layers "F.Cu" "F.Mask" "F.Paste")
			(net "P3V3_OCP_EN_1_R")
		)
	)
	(footprint ""
		(layer "F.Cu")
		(at 72.463914 -146.735292 180)
		(property "Reference" "PC64"
			(at 0 0 180)
			(layer "F.SilkS")
			(hide yes)
			(effects
				(font
					(size 1.27 1.27)
				)
			)
		)
		(property "Value" ""
			(at 0 0 180)
			(layer "F.Fab")
			(effects
				(font
					(size 1.27 1.27)
				)
			)
		)
		(duplicate_pad_numbers_are_jumpers no)
		(fp_line
			(start 0.7874 0.4064)
			(end -0.7874 0.4064)
			(stroke
				(width 0.1524)
				(type default)
			)
			(layer "F.SilkS")
		)
		(fp_line
			(start 0.7874 -0.4064)
			(end 0.7874 0.4064)
			(stroke
				(width 0.1524)
				(type default)
			)
			(layer "F.SilkS")
		)
		(fp_line
			(start -0.7874 0.4064)
			(end -0.7874 -0.4064)
			(stroke
				(width 0.1524)
				(type default)
			)
			(layer "F.SilkS")
		)
		(fp_line
			(start -0.7874 -0.4064)
			(end 0.7874 -0.4064)
			(stroke
				(width 0.1524)
				(type default)
			)
			(layer "F.SilkS")
		)
		(fp_line
			(start 0.67945 0.3048)
			(end 0.120396 0.3048)
			(stroke
				(width 0.1)
				(type default)
			)
			(layer "F.Fab")
		)
		(fp_line
			(start 0.67945 -0.3048)
			(end 0.67945 0.3048)
			(stroke
				(width 0.1)
				(type default)
			)
			(layer "F.Fab")
		)
		(fp_line
			(start 0.12065 -0.2794)
			(end 0.12065 -0.3048)
			(stroke
				(width 0.1)
				(type default)
			)
			(layer "F.Fab")
		)
		(fp_line
			(start 0.12065 -0.3048)
			(end 0.67945 -0.3048)
			(stroke
				(width 0.1)
				(type default)
			)
			(layer "F.Fab")
		)
		(fp_line
			(start 0.120396 0.3048)
			(end 0.120396 0.2794)
			(stroke
				(width 0.1)
				(type default)
			)
			(layer "F.Fab")
		)
		(fp_line
			(start 0.120396 0.2794)
			(end -0.12065 0.2794)
			(stroke
				(width 0.1)
				(type default)
			)
			(layer "F.Fab")
		)
		(fp_line
			(start -0.12065 0.3048)
			(end -0.67945 0.3048)
			(stroke
				(width 0.1)
				(type default)
			)
			(layer "F.Fab")
		)
		(fp_line
			(start -0.12065 0.2794)
			(end -0.12065 0.3048)
			(stroke
				(width 0.1)
				(type default)
			)
			(layer "F.Fab")
		)
		(fp_line
			(start -0.12065 -0.2794)
			(end 0.12065 -0.2794)
			(stroke
				(width 0.1)
				(type default)
			)
			(layer "F.Fab")
		)
		(fp_line
			(start -0.12065 -0.305054)
			(end -0.12065 -0.2794)
			(stroke
				(width 0.1)
				(type default)
			)
			(layer "F.Fab")
		)
		(fp_line
			(start -0.67945 0.3048)
			(end -0.67945 -0.305054)
			(stroke
				(width 0.1)
				(type default)
			)
			(layer "F.Fab")
		)
		(fp_line
			(start -0.67945 -0.305054)
			(end -0.12065 -0.305054)
			(stroke
				(width 0.1)
				(type default)
			)
			(layer "F.Fab")
		)
		(pad "1" smd circle
			(at -0.40005 0 180)
			(size 0 0)
			(layers "F.Cu" "F.Mask" "F.Paste")
			(net "PVDD18_S5_P1_FB")
		)
		(pad "2" smd circle
			(at 0.40005 0 180)
			(size 0 0)
			(layers "F.Cu" "F.Mask" "F.Paste")
			(net "PVDD18_S5_P1_FB_RC")
		)
	)
	(footprint ""
		(layer "F.Cu")
		(at 331.494892 -389.86206 180)
		(property "Reference" "C964"
			(at 0 0 180)
			(layer "F.SilkS")
			(hide yes)
			(effects
				(font
					(size 1.27 1.27)
				)
			)
		)
		(property "Value" ""
			(at 0 0 180)
			(layer "F.Fab")
			(effects
				(font
					(size 1.27 1.27)
				)
			)
		)
		(duplicate_pad_numbers_are_jumpers no)
		(fp_line
			(start 0.299974 0.150114)
			(end -0.299974 0.150114)
			(stroke
				(width 0.1)
				(type default)
			)
			(layer "F.Fab")
		)
		(fp_line
			(start 0.299974 -0.150114)
			(end 0.299974 0.150114)
			(stroke
				(width 0.1)
				(type default)
			)
			(layer "F.Fab")
		)
		(fp_line
			(start -0.299974 0.150114)
			(end -0.299974 -0.150114)
			(stroke
				(width 0.1)
				(type default)
			)
			(layer "F.Fab")
		)
		(fp_line
			(start -0.299974 -0.150114)
			(end 0.299974 -0.150114)
			(stroke
				(width 0.1)
				(type default)
			)
			(layer "F.Fab")
		)
		(pad "1" smd rect
			(at -0.2667 0 180)
			(size 0.3048 0.381)
			(layers "F.Cu" "F.Mask" "F.Paste")
			(net "P5E_CPU0_P1_TX_C_DN<0>")
		)
		(pad "2" smd rect
			(at 0.2667 0 180)
			(size 0.3048 0.381)
			(layers "F.Cu" "F.Mask" "F.Paste")
			(net "P5E_CPU0_P1_TX_DN<0>")
		)
	)
)
